(kicad_pcb
	(version 20260206)
	(generator "pcbnew")
	(generator_version "10.0")
	(general
		(thickness 1.6)
		(legacy_teardrops no)
	)
	(paper "A4")
	(title_block
		(title "panther-plus-userver — 13130-1b_20150205.brd")
		(comment 1 "Honey Badger (Wiwynn) / footprints 1096-1102 of 1509")
	)
	(layers
		(0 "F.Cu" signal "TOP")
		(4 "In1.Cu" signal "L2")
		(6 "In2.Cu" signal "L3")
		(8 "In3.Cu" signal "L4")
		(10 "In4.Cu" signal "L5")
		(12 "In5.Cu" signal "L6")
		(14 "In6.Cu" signal "L7")
		(16 "In7.Cu" signal "L8")
		(18 "In8.Cu" signal "L9")
		(20 "In9.Cu" signal "L10")
		(22 "In10.Cu" signal "L11")
		(2 "B.Cu" signal "BOTTOM")
		(9 "F.Adhes" user "F.Adhesive")
		(11 "B.Adhes" user "B.Adhesive")
		(13 "F.Paste" user "Package Geometry/Pastemask Top")
		(15 "B.Paste" user "Package Geometry/Pastemask Bottom")
		(5 "F.SilkS" user "Ref Des/Silkscreen Top")
		(7 "B.SilkS" user "Ref Des/Silkscreen Bottom")
		(1 "F.Mask" user "Board Geometry/Soldermask Top")
		(3 "B.Mask" user "Board Geometry/Soldermask Bottom")
		(17 "Dwgs.User" user "User.Drawings")
		(19 "Cmts.User" user "User.Comments")
		(21 "Eco1.User" user "User.Eco1")
		(23 "Eco2.User" user "User.Eco2")
		(25 "Edge.Cuts" user "Board Geometry/Outline")
		(27 "Margin" user)
		(31 "F.CrtYd" user "Package Geometry/Place Bound Top")
		(29 "B.CrtYd" user "Package Geometry/Place Bound Bottom")
		(35 "F.Fab" user "Ref Des/Assembly Top")
		(33 "B.Fab" user "Ref Des/Assembly Bottom")
	)
	(footprint ""
		(layer "B.Cu")
		(at 197.4596 -64.5922 -90)
		(property "Reference" "PC168"
			(at 0 0 90)
			(layer "B.SilkS")
			(hide yes)
			(effects
				(font
					(size 1.27 1.27)
				)
				(justify mirror)
			)
		)
		(property "Value" "SC10U6D3V3MX-GP"
			(at 0.0254 -2.0193 270)
			(unlocked yes)
			(layer "B.Fab")
			(hide yes)
			(effects
				(font
					(size 1.016 1.016)
					(thickness 0.1524)
				)
				(justify mirror)
			)
		)
		(property "Device Type" "C603H38"
			(at 0.0254 -3.5433 270)
			(unlocked yes)
			(layer "B.Fab")
			(hide yes)
			(effects
				(font
					(size 1.016 1.016)
					(thickness 0.1524)
				)
				(justify mirror)
			)
		)
		(duplicate_pad_numbers_are_jumpers no)
		(fp_line
			(start 0.4064 0)
			(end -0.4064 0)
			(stroke
				(width 0.2286)
				(type default)
			)
			(layer "B.SilkS")
		)
		(fp_rect
			(start 0.635 1.1811)
			(end -0.635 -1.1811)
			(stroke
				(width 0)
				(type default)
			)
			(fill no)
			(layer "B.CrtYd")
		)
		(fp_rect
			(start 0.635 1.1811)
			(end -0.635 -1.1811)
			(stroke
				(width 0)
				(type default)
			)
			(fill no)
			(layer "B.Fab")
		)
		(pad "1" smd custom
			(at 0 -0.6604 90)
			(size 0.19685 0.19685)
			(layers "B.Cu" "B.Mask" "B.Paste")
			(net "PV_VDDR")
			(options
				(clearance outline)
				(anchor circle)
			)
			(primitives
				(gr_poly
					(pts
						(arc
							(start 0.508 0.2921)
							(mid 0.478242 0.363942)
							(end 0.4064 0.3937)
						)
						(arc
							(start -0.4064 0.3937)
							(mid -0.478242 0.363942)
							(end -0.508 0.2921)
						)
						(arc
							(start -0.508 -0.2921)
							(mid -0.478242 -0.363942)
							(end -0.4064 -0.3937)
						)
						(arc
							(start 0.4064 -0.3937)
							(mid 0.478242 -0.363942)
							(end 0.508 -0.2921)
						)
					)
					(width 0)
					(fill yes)
				)
			)
		)
		(pad "2" smd custom
			(at 0 0.6604 90)
			(size 0.19685 0.19685)
			(layers "B.Cu" "B.Mask" "B.Paste")
			(net "GND")
			(options
				(clearance outline)
				(anchor circle)
			)
			(primitives
				(gr_poly
					(pts
						(arc
							(start 0.508 0.2921)
							(mid 0.478242 0.363942)
							(end 0.4064 0.3937)
						)
						(arc
							(start -0.4064 0.3937)
							(mid -0.478242 0.363942)
							(end -0.508 0.2921)
						)
						(arc
							(start -0.508 -0.2921)
							(mid -0.478242 -0.363942)
							(end -0.4064 -0.3937)
						)
						(arc
							(start 0.4064 -0.3937)
							(mid 0.478242 -0.363942)
							(end 0.508 -0.2921)
						)
					)
					(width 0)
					(fill yes)
				)
			)
		)
	)
	(footprint ""
		(layer "B.Cu")
		(at 74.041 -30.988 90)
		(property "Reference" "R121"
			(at 0 0 90)
			(layer "B.SilkS")
			(hide yes)
			(effects
				(font
					(size 1.27 1.27)
				)
				(justify mirror)
			)
		)
		(property "Value" "10KR2F-2-GP"
			(at -0.064008 -3.993896 90)
			(unlocked yes)
			(layer "B.Fab")
			(hide yes)
			(effects
				(font
					(size 1.016 1.016)
					(thickness 0.1524)
				)
				(justify mirror)
			)
		)
		(property "Device Type" "R402H16"
			(at -0.064008 -5.517896 90)
			(unlocked yes)
			(layer "B.Fab")
			(hide yes)
			(effects
				(font
					(size 1.016 1.016)
					(thickness 0.1524)
				)
				(justify mirror)
			)
		)
		(duplicate_pad_numbers_are_jumpers no)
		(fp_rect
			(start 0.381 0.8382)
			(end -0.381 -0.8382)
			(stroke
				(width 0)
				(type default)
			)
			(fill no)
			(layer "B.CrtYd")
		)
		(fp_rect
			(start 0.381 0.8382)
			(end -0.381 -0.8382)
			(stroke
				(width 0)
				(type default)
			)
			(fill no)
			(layer "B.Fab")
		)
		(pad "1" smd custom
			(at 0 -0.4318 270)
			(size 0.127 0.127)
			(layers "B.Cu" "B.Mask" "B.Paste")
			(net "P3V3_CPU")
			(options
				(clearance outline)
				(anchor circle)
			)
			(primitives
				(gr_poly
					(pts
						(arc
							(start -0.2032 0.2794)
							(mid -0.239121 0.264521)
							(end -0.254 0.2286)
						)
						(arc
							(start -0.254 -0.2286)
							(mid -0.239121 -0.264521)
							(end -0.2032 -0.2794)
						)
						(arc
							(start 0.2032 -0.2794)
							(mid 0.239121 -0.264521)
							(end 0.254 -0.2286)
						)
						(arc
							(start 0.254 0.2286)
							(mid 0.239121 0.264521)
							(end 0.2032 0.2794)
						)
					)
					(width 0)
					(fill yes)
				)
			)
		)
		(pad "2" smd custom
			(at 0 0.4318 270)
			(size 0.127 0.127)
			(layers "B.Cu" "B.Mask" "B.Paste")
			(net "SUSPWRDNACK")
			(options
				(clearance outline)
				(anchor circle)
			)
			(primitives
				(gr_poly
					(pts
						(arc
							(start -0.2032 0.2794)
							(mid -0.239121 0.264521)
							(end -0.254 0.2286)
						)
						(arc
							(start -0.254 -0.2286)
							(mid -0.239121 -0.264521)
							(end -0.2032 -0.2794)
						)
						(arc
							(start 0.2032 -0.2794)
							(mid 0.239121 -0.264521)
							(end 0.254 -0.2286)
						)
						(arc
							(start 0.254 0.2286)
							(mid 0.239121 0.264521)
							(end 0.2032 0.2794)
						)
					)
					(width 0)
					(fill yes)
				)
			)
		)
	)
	(footprint ""
		(layer "B.Cu")
		(at 95.631 -52.197 180)
		(property "Reference" "C119"
			(at 0 0 0)
			(layer "B.SilkS")
			(hide yes)
			(effects
				(font
					(size 1.27 1.27)
				)
				(justify mirror)
			)
		)
		(property "Value" "SC1U25V3KX-GP"
			(at 0 -2.8194 180)
			(unlocked yes)
			(layer "B.Fab")
			(hide yes)
			(effects
				(font
					(size 1.016 1.016)
					(thickness 0.1524)
				)
				(justify mirror)
			)
		)
		(property "Device Type" "C603H36"
			(at 0 -4.3434 180)
			(unlocked yes)
			(layer "B.Fab")
			(hide yes)
			(effects
				(font
					(size 1.016 1.016)
					(thickness 0.1524)
				)
				(justify mirror)
			)
		)
		(duplicate_pad_numbers_are_jumpers no)
		(fp_line
			(start 0.4064 0)
			(end -0.4064 0)
			(stroke
				(width 0.2286)
				(type default)
			)
			(layer "B.SilkS")
		)
		(fp_rect
			(start 0.635 1.1811)
			(end -0.635 -1.1811)
			(stroke
				(width 0)
				(type default)
			)
			(fill no)
			(layer "B.CrtYd")
		)
		(fp_rect
			(start 0.635 1.1811)
			(end -0.635 -1.1811)
			(stroke
				(width 0)
				(type default)
			)
			(fill no)
			(layer "B.Fab")
		)
		(pad "1" smd custom
			(at 0 -0.6604)
			(size 0.19685 0.19685)
			(layers "B.Cu" "B.Mask" "B.Paste")
			(net "VCCACKDDR0")
			(options
				(clearance outline)
				(anchor circle)
			)
			(primitives
				(gr_poly
					(pts
						(arc
							(start 0.508 0.2921)
							(mid 0.478242 0.363942)
							(end 0.4064 0.3937)
						)
						(arc
							(start -0.4064 0.3937)
							(mid -0.478242 0.363942)
							(end -0.508 0.2921)
						)
						(arc
							(start -0.508 -0.2921)
							(mid -0.478242 -0.363942)
							(end -0.4064 -0.3937)
						)
						(arc
							(start 0.4064 -0.3937)
							(mid 0.478242 -0.363942)
							(end 0.508 -0.2921)
						)
					)
					(width 0)
					(fill yes)
				)
			)
		)
		(pad "2" smd custom
			(at 0 0.6604)
			(size 0.19685 0.19685)
			(layers "B.Cu" "B.Mask" "B.Paste")
			(net "GND")
			(options
				(clearance outline)
				(anchor circle)
			)
			(primitives
				(gr_poly
					(pts
						(arc
							(start 0.508 0.2921)
							(mid 0.478242 0.363942)
							(end 0.4064 0.3937)
						)
						(arc
							(start -0.4064 0.3937)
							(mid -0.478242 0.363942)
							(end -0.508 0.2921)
						)
						(arc
							(start -0.508 -0.2921)
							(mid -0.478242 -0.363942)
							(end -0.4064 -0.3937)
						)
						(arc
							(start 0.4064 -0.3937)
							(mid 0.478242 -0.363942)
							(end 0.508 -0.2921)
						)
					)
					(width 0)
					(fill yes)
				)
			)
		)
	)
	(footprint ""
		(layer "B.Cu")
		(at 149.733 -59.309)
		(property "Reference" "C360"
			(at 0 0 0)
			(layer "B.SilkS")
			(hide yes)
			(effects
				(font
					(size 1.27 1.27)
				)
				(justify mirror)
			)
		)
		(property "Value" "SC47U6D3V5MX-1-GP"
			(at 0 -4.9022 0)
			(unlocked yes)
			(layer "B.Fab")
			(hide yes)
			(effects
				(font
					(size 1.016 1.016)
					(thickness 0.1524)
				)
				(justify mirror)
			)
		)
		(property "Device Type" "C805H54"
			(at 0 -6.8072 0)
			(unlocked yes)
			(layer "B.Fab")
			(hide yes)
			(effects
				(font
					(size 1.016 1.016)
					(thickness 0.1524)
				)
				(justify mirror)
			)
		)
		(duplicate_pad_numbers_are_jumpers no)
		(fp_line
			(start -0.6096 0)
			(end 0.6096 0)
			(stroke
				(width 0.3048)
				(type default)
			)
			(layer "B.SilkS")
		)
		(fp_poly
			(pts
				(xy 0.9017 1.4351) (xy -0.9017 1.4351) (xy -0.9017 -1.4351) (xy 0.9017 -1.4351)
			)
			(stroke
				(width 0)
				(type default)
			)
			(fill no)
			(layer "B.CrtYd")
		)
		(fp_poly
			(pts
				(xy -0.9017 1.4351) (xy -0.9017 -1.4351) (xy 0.9017 -1.4351) (xy 0.9017 1.4351)
			)
			(stroke
				(width 0)
				(type default)
			)
			(fill no)
			(layer "B.Fab")
		)
		(pad "1" smd rect
			(at 0 -0.8382 180)
			(size 1.5494 0.9398)
			(layers "B.Cu" "B.Mask" "B.Paste")
			(net "PV_VDDR")
		)
		(pad "2" smd rect
			(at 0 0.8382 180)
			(size 1.5494 0.9398)
			(layers "B.Cu" "B.Mask" "B.Paste")
			(net "GND")
		)
	)
	(footprint ""
		(layer "B.Cu")
		(at 48.641 -14.605 90)
		(property "Reference" "R425"
			(at 0 0 90)
			(layer "B.SilkS")
			(hide yes)
			(effects
				(font
					(size 1.27 1.27)
				)
				(justify mirror)
			)
		)
		(property "Value" "43D2R2F-GP"
			(at -1.7907 -1.1176 90)
			(unlocked yes)
			(layer "B.Fab")
			(hide yes)
			(effects
				(font
					(size 1.016 1.016)
					(thickness 0.1524)
				)
				(justify mirror)
			)
		)
		(property "Device Type" "R402H16"
			(at -1.7907 -2.6416 90)
			(unlocked yes)
			(layer "B.Fab")
			(hide yes)
			(effects
				(font
					(size 1.016 1.016)
					(thickness 0.1524)
				)
				(justify mirror)
			)
		)
		(duplicate_pad_numbers_are_jumpers no)
		(fp_rect
			(start 0.381 0.8382)
			(end -0.381 -0.8382)
			(stroke
				(width 0)
				(type default)
			)
			(fill no)
			(layer "B.CrtYd")
		)
		(fp_rect
			(start 0.381 0.8382)
			(end -0.381 -0.8382)
			(stroke
				(width 0)
				(type default)
			)
			(fill no)
			(layer "B.Fab")
		)
		(pad "1" smd custom
			(at 0 -0.4318 270)
			(size 0.127 0.127)
			(layers "B.Cu" "B.Mask" "B.Paste")
			(net "CLK_100M_PCIE2_REFCLK_DP")
			(options
				(clearance outline)
				(anchor circle)
			)
			(primitives
				(gr_poly
					(pts
						(arc
							(start -0.2032 0.2794)
							(mid -0.239121 0.264521)
							(end -0.254 0.2286)
						)
						(arc
							(start -0.254 -0.2286)
							(mid -0.239121 -0.264521)
							(end -0.2032 -0.2794)
						)
						(arc
							(start 0.2032 -0.2794)
							(mid 0.239121 -0.264521)
							(end 0.254 -0.2286)
						)
						(arc
							(start 0.254 0.2286)
							(mid 0.239121 0.264521)
							(end 0.2032 0.2794)
						)
					)
					(width 0)
					(fill yes)
				)
			)
		)
		(pad "2" smd custom
			(at 0 0.4318 270)
			(size 0.127 0.127)
			(layers "B.Cu" "B.Mask" "B.Paste")
			(net "GND")
			(options
				(clearance outline)
				(anchor circle)
			)
			(primitives
				(gr_poly
					(pts
						(arc
							(start -0.2032 0.2794)
							(mid -0.239121 0.264521)
							(end -0.254 0.2286)
						)
						(arc
							(start -0.254 -0.2286)
							(mid -0.239121 -0.264521)
							(end -0.2032 -0.2794)
						)
						(arc
							(start 0.2032 -0.2794)
							(mid 0.239121 -0.264521)
							(end 0.254 -0.2286)
						)
						(arc
							(start 0.254 0.2286)
							(mid 0.239121 0.264521)
							(end 0.2032 0.2794)
						)
					)
					(width 0)
					(fill yes)
				)
			)
		)
	)
	(footprint ""
		(layer "B.Cu")
		(at 82.931 -62.865)
		(property "Reference" "R266"
			(at 0 0 0)
			(layer "B.SilkS")
			(hide yes)
			(effects
				(font
					(size 1.27 1.27)
				)
				(justify mirror)
			)
		)
		(property "Value" "240R3-GP"
			(at 0.0254 -2.5146 0)
			(unlocked yes)
			(layer "B.Fab")
			(hide yes)
			(effects
				(font
					(size 1.016 1.016)
					(thickness 0.1524)
				)
				(justify mirror)
			)
		)
		(property "Device Type" "R603H22"
			(at 0.0254 -4.0386 0)
			(unlocked yes)
			(layer "B.Fab")
			(hide yes)
			(effects
				(font
					(size 1.016 1.016)
					(thickness 0.1524)
				)
				(justify mirror)
			)
		)
		(duplicate_pad_numbers_are_jumpers no)
		(fp_line
			(start -0.4318 0)
			(end -0.2032 0)
			(stroke
				(width 0.2032)
				(type default)
			)
			(layer "B.SilkS")
		)
		(fp_line
			(start 0.2032 0)
			(end 0.4191 0)
			(stroke
				(width 0.2032)
				(type default)
			)
			(layer "B.SilkS")
		)
		(fp_rect
			(start 0.635 1.1811)
			(end -0.635 -1.1811)
			(stroke
				(width 0)
				(type default)
			)
			(fill no)
			(layer "B.CrtYd")
		)
		(fp_rect
			(start 0.635 1.1811)
			(end -0.635 -1.1811)
			(stroke
				(width 0)
				(type default)
			)
			(fill no)
			(layer "B.Fab")
		)
		(pad "1" smd custom
			(at 0 -0.6604 180)
			(size 0.19685 0.19685)
			(layers "B.Cu" "B.Mask" "B.Paste")
			(net "P1V0")
			(options
				(clearance outline)
				(anchor circle)
			)
			(primitives
				(gr_poly
					(pts
						(arc
							(start 0.508 0.2921)
							(mid 0.478242 0.363942)
							(end 0.4064 0.3937)
						)
						(arc
							(start -0.4064 0.3937)
							(mid -0.478242 0.363942)
							(end -0.508 0.2921)
						)
						(arc
							(start -0.508 -0.2921)
							(mid -0.478242 -0.363942)
							(end -0.4064 -0.3937)
						)
						(arc
							(start 0.4064 -0.3937)
							(mid 0.478242 -0.363942)
							(end 0.508 -0.2921)
						)
					)
					(width 0)
					(fill yes)
				)
			)
		)
		(pad "2" smd custom
			(at 0 0.6604 180)
			(size 0.19685 0.19685)
			(layers "B.Cu" "B.Mask" "B.Paste")
			(net "PROCESSOR_HOT#")
			(options
				(clearance outline)
				(anchor circle)
			)
			(primitives
				(gr_poly
					(pts
						(arc
							(start 0.508 0.2921)
							(mid 0.478242 0.363942)
							(end 0.4064 0.3937)
						)
						(arc
							(start -0.4064 0.3937)
							(mid -0.478242 0.363942)
							(end -0.508 0.2921)
						)
						(arc
							(start -0.508 -0.2921)
							(mid -0.478242 -0.363942)
							(end -0.4064 -0.3937)
						)
						(arc
							(start 0.4064 -0.3937)
							(mid 0.478242 -0.363942)
							(end 0.508 -0.2921)
						)
					)
					(width 0)
					(fill yes)
				)
			)
		)
	)
	(footprint ""
		(layer "B.Cu")
		(at 73.533 -52.324 -90)
		(property "Reference" "Q11"
			(at 0 0 90)
			(layer "B.SilkS")
			(hide yes)
			(effects
				(font
					(size 1.27 1.27)
				)
				(justify mirror)
			)
		)
		(property "Value" "MMBT3904TT1G-GP"
			(at 0 -9.7282 270)
			(unlocked yes)
			(layer "B.Fab")
			(hide yes)
			(effects
				(font
					(size 1.016 1.016)
					(thickness 0.1524)
				)
				(justify mirror)
			)
		)
		(property "Device Type" "SC75CBE1D6H36"
			(at 0 -11.6332 270)
			(unlocked yes)
			(layer "B.Fab")
			(hide yes)
			(effects
				(font
					(size 1.016 1.016)
					(thickness 0.1524)
				)
				(justify mirror)
			)
		)
		(duplicate_pad_numbers_are_jumpers no)
		(fp_poly
			(pts
				(xy -0.381 -1.1938) (xy 0.381 -1.1938) (xy 0.381 -0.6604) (xy 1.0541 -0.6604) (xy 1.0541 0.6604)
				(xy 0.889 0.6604) (xy 0.889 1.1938) (xy -0.889 1.1938) (xy -0.889 0.6604) (xy -1.0541 0.6604) (xy -1.0541 -0.6604)
				(xy -0.381 -0.6604)
			)
			(stroke
				(width 0)
				(type default)
			)
			(fill no)
			(layer "B.CrtYd")
		)
		(fp_poly
			(pts
				(xy -0.381 -1.1938) (xy 0.381 -1.1938) (xy 0.381 -0.6604) (xy 1.0541 -0.6604) (xy 1.0541 0.6604)
				(xy 0.889 0.6604) (xy 0.889 1.1938) (xy -0.889 1.1938) (xy -0.889 0.6604) (xy -1.0541 0.6604) (xy -1.0541 -0.6604)
				(xy -0.381 -0.6604)
			)
			(stroke
				(width 0)
				(type default)
			)
			(fill no)
			(layer "B.Fab")
		)
		(pad "B" smd custom
			(at 0.508 0.6604 90)
			(size 0.127 0.127)
			(layers "B.Cu" "B.Mask" "B.Paste")
			(net "MEMORY_HOT_N_LV_B1")
			(options
				(clearance outline)
				(anchor circle)
			)
			(primitives
				(gr_poly
					(pts
						(arc
							(start -0.0508 -0.4064)
							(mid -0.194484 -0.346884)
							(end -0.254 -0.2032)
						)
						(arc
							(start -0.254 0.2032)
							(mid -0.194484 0.346884)
							(end -0.0508 0.4064)
						)
						(arc
							(start 0.0508 0.4064)
							(mid 0.194484 0.346884)
							(end 0.254 0.2032)
						)
						(arc
							(start 0.254 -0.2032)
							(mid 0.194484 -0.346884)
							(end 0.0508 -0.4064)
						)
					)
					(width 0)
					(fill yes)
				)
			)
		)
		(pad "C" smd custom
			(at 0 -0.6604 90)
			(size 0.127 0.127)
			(layers "B.Cu" "B.Mask" "B.Paste")
			(net "MEMORY_CPU_HOT#")
			(options
				(clearance outline)
				(anchor circle)
			)
			(primitives
				(gr_poly
					(pts
						(arc
							(start -0.0508 -0.4064)
							(mid -0.194484 -0.346884)
							(end -0.254 -0.2032)
						)
						(arc
							(start -0.254 0.2032)
							(mid -0.194484 0.346884)
							(end -0.0508 0.4064)
						)
						(arc
							(start 0.0508 0.4064)
							(mid 0.194484 0.346884)
							(end 0.254 0.2032)
						)
						(arc
							(start 0.254 -0.2032)
							(mid 0.194484 -0.346884)
							(end 0.0508 -0.4064)
						)
					)
					(width 0)
					(fill yes)
				)
			)
		)
		(pad "E" smd custom
			(at -0.508 0.6604 90)
			(size 0.127 0.127)
			(layers "B.Cu" "B.Mask" "B.Paste")
			(net "MEMORY_HOT_LV_E1#")
			(options
				(clearance outline)
				(anchor circle)
			)
			(primitives
				(gr_poly
					(pts
						(arc
							(start -0.0508 -0.4064)
							(mid -0.194484 -0.346884)
							(end -0.254 -0.2032)
						)
						(arc
							(start -0.254 0.2032)
							(mid -0.194484 0.346884)
							(end -0.0508 0.4064)
						)
						(arc
							(start 0.0508 0.4064)
							(mid 0.194484 0.346884)
							(end 0.254 0.2032)
						)
						(arc
							(start 0.254 -0.2032)
							(mid 0.194484 -0.346884)
							(end 0.0508 -0.4064)
						)
					)
					(width 0)
					(fill yes)
				)
			)
		)
	)
)
